G04*
G04 #@! TF.GenerationSoftware,Altium Limited,Altium Designer,23.6.0 (18)*
G04*
G04 Layer_Color=0*
%FSLAX44Y44*%
%MOMM*%
G71*
G04*
G04 #@! TF.SameCoordinates,59133E90-4310-4D8A-9E2C-91A8D2F69FBB*
G04*
G04*
G04 #@! TF.FilePolarity,Positive*
G04*
G01*
G75*
%ADD65C,0.0254*%
D65*
X10750Y0D02*
Y26500D01*
D02*
G03*
X5750Y31500I-5000J0D01*
G01*
X0D01*
X-0Y420000D01*
X220000D01*
X220000Y31500D01*
X214250D01*
D02*
G03*
X209250Y26500I0J-5000D01*
G01*
Y0D01*
X172250D01*
Y29000D01*
D02*
G03*
X160250Y29000I-6000J0D01*
G01*
Y0D01*
X10750D01*
M02*
